(kicad_pcb
	(version 20260206)
	(generator "pcbnew")
	(generator_version "10.0")
	(general
		(thickness 1.6)
		(legacy_teardrops no)
	)
	(paper "A4")
	(title_block
		(title "Wiwynn_Tioga_Pass_MB.brd")
		(comment 1 "Tioga Pass / footprints 632-635 of 4770")
	)
	(layers
		(0 "F.Cu" signal "TOP")
		(4 "In1.Cu" signal "L2GND")
		(6 "In2.Cu" signal "L3")
		(8 "In3.Cu" signal "L4GND")
		(10 "In4.Cu" signal "L5")
		(12 "In5.Cu" signal "L6GND")
		(14 "In6.Cu" signal "L7VCC")
		(16 "In7.Cu" signal "L8VCC")
		(18 "In8.Cu" signal "L9GND")
		(20 "In9.Cu" signal "L10")
		(22 "In10.Cu" signal "L11GND")
		(24 "In11.Cu" signal "L12")
		(26 "In12.Cu" signal "L13GND")
		(2 "B.Cu" signal "BOTTOM")
		(9 "F.Adhes" user "F.Adhesive")
		(11 "B.Adhes" user "B.Adhesive")
		(13 "F.Paste" user "Package Geometry/Pastemask Top")
		(15 "B.Paste" user "Package Geometry/Pastemask Bottom")
		(5 "F.SilkS" user "Ref Des/Silkscreen Top")
		(7 "B.SilkS" user "Ref Des/Silkscreen Bottom")
		(1 "F.Mask" user "Board Geometry/Soldermask Top")
		(3 "B.Mask" user "Board Geometry/Soldermask Bottom")
		(17 "Dwgs.User" user "User.Drawings")
		(19 "Cmts.User" user "User.Comments")
		(21 "Eco1.User" user "User.Eco1")
		(23 "Eco2.User" user "User.Eco2")
		(25 "Edge.Cuts" user "Board Geometry/Outline")
		(27 "Margin" user)
		(31 "F.CrtYd" user "Package Geometry/Place Bound Top")
		(29 "B.CrtYd" user "Package Geometry/Place Bound Bottom")
		(35 "F.Fab" user "Ref Des/Assembly Top")
		(33 "B.Fab" user "Ref Des/Assembly Bottom")
	)
	(footprint ""
		(layer "F.Cu")
		(at 399.770092 -0.109474 90)
		(property "Reference" "R7G114"
			(at -0.8382 -0.67818 90)
			(unlocked yes)
			(layer "F.SilkS")
			(effects
				(font
					(size 0.4064 0.254)
					(thickness 0.1524)
				)
				(justify left)
			)
		)
		(property "Value" ""
			(at 0 0 90)
			(layer "F.Fab")
			(effects
				(font
					(size 1.27 1.27)
				)
			)
		)
		(duplicate_pad_numbers_are_jumpers no)
		(fp_poly
			(pts
				(xy -0.2794 -0.1016) (xy 0.2794 -0.1016) (xy 0.2794 0.9906) (xy -0.2794 0.9906)
			)
			(stroke
				(width 0)
				(type default)
			)
			(fill no)
			(layer "F.CrtYd")
		)
		(fp_line
			(start 0.2794 -0.1016)
			(end -0.2794 -0.1016)
			(stroke
				(width 0.1)
				(type default)
			)
			(layer "F.Fab")
		)
		(fp_line
			(start -0.2794 -0.1016)
			(end -0.2794 0.9906)
			(stroke
				(width 0.1)
				(type default)
			)
			(layer "F.Fab")
		)
		(fp_line
			(start 0.2794 0.9906)
			(end 0.2794 -0.1016)
			(stroke
				(width 0.1)
				(type default)
			)
			(layer "F.Fab")
		)
		(fp_line
			(start -0.2794 0.9906)
			(end 0.2794 0.9906)
			(stroke
				(width 0.1)
				(type default)
			)
			(layer "F.Fab")
		)
		(pad "1" smd rect
			(at 0 0 90)
			(size 0.508 0.508)
			(layers "F.Cu" "F.Mask" "F.Paste")
			(net "BMC_JTAG_SEL_N")
		)
		(pad "2" smd rect
			(at 0 0.889 90)
			(size 0.508 0.508)
			(layers "F.Cu" "F.Mask" "F.Paste")
			(net "BMC_JTAG_SEL_N_MUX")
		)
		(zone
			(layer "F.Cu")
			(hatch none 0.5)
			(connect_pads
				(clearance 0)
			)
			(min_thickness 0.25)
			(keepout
				(tracks allowed)
				(vias not_allowed)
				(pads allowed)
				(copperpour not_allowed)
				(footprints allowed)
			)
			(placement
				(enabled no)
				(sheetname "")
			)
			(fill
				(thermal_gap 0.5)
				(thermal_bridge_width 0.5)
				(island_removal_mode 0)
			)
			(polygon
				(pts
					(xy 400.024092 0.144526) (xy 400.024092 -0.363474) (xy 400.405092 -0.363474) (xy 400.405092 0.144526)
				)
			)
		)
		(zone
			(layer "F.Cu")
			(hatch none 0.5)
			(connect_pads
				(clearance 0)
			)
			(min_thickness 0.25)
			(keepout
				(tracks not_allowed)
				(vias allowed)
				(pads allowed)
				(copperpour not_allowed)
				(footprints allowed)
			)
			(placement
				(enabled no)
				(sheetname "")
			)
			(fill
				(thermal_gap 0.5)
				(thermal_bridge_width 0.5)
				(island_removal_mode 0)
			)
			(polygon
				(pts
					(xy 400.405092 0.144526) (xy 400.405092 -0.363474) (xy 400.024092 -0.363474) (xy 400.024092 0.144526)
				)
			)
		)
	)
	(footprint ""
		(layer "F.Cu")
		(at 368.0206 -136.4234 180)
		(property "Reference" "R7A18"
			(at 0 0 180)
			(layer "F.SilkS")
			(hide yes)
			(effects
				(font
					(size 1.27 1.27)
				)
			)
		)
		(property "Value" ""
			(at 0 0 180)
			(layer "F.Fab")
			(effects
				(font
					(size 1.27 1.27)
				)
			)
		)
		(duplicate_pad_numbers_are_jumpers no)
		(fp_poly
			(pts
				(xy -0.2794 -0.1016) (xy 0.2794 -0.1016) (xy 0.2794 0.9906) (xy -0.2794 0.9906)
			)
			(stroke
				(width 0)
				(type default)
			)
			(fill no)
			(layer "F.CrtYd")
		)
		(fp_line
			(start 0.2794 0.9906)
			(end 0.2794 -0.1016)
			(stroke
				(width 0.1)
				(type default)
			)
			(layer "F.Fab")
		)
		(fp_line
			(start 0.2794 -0.1016)
			(end -0.2794 -0.1016)
			(stroke
				(width 0.1)
				(type default)
			)
			(layer "F.Fab")
		)
		(fp_line
			(start -0.2794 0.9906)
			(end 0.2794 0.9906)
			(stroke
				(width 0.1)
				(type default)
			)
			(layer "F.Fab")
		)
		(fp_line
			(start -0.2794 -0.1016)
			(end -0.2794 0.9906)
			(stroke
				(width 0.1)
				(type default)
			)
			(layer "F.Fab")
		)
		(pad "1" smd rect
			(at 0 0 180)
			(size 0.508 0.508)
			(layers "F.Cu" "F.Mask" "F.Paste")
			(net "GND")
		)
		(pad "2" smd rect
			(at 0 0.889 180)
			(size 0.508 0.508)
			(layers "F.Cu" "F.Mask" "F.Paste")
			(net "VSENSE_PVNN_PCH_STBY_AVSN")
		)
		(zone
			(layer "F.Cu")
			(hatch none 0.5)
			(connect_pads
				(clearance 0)
			)
			(min_thickness 0.25)
			(keepout
				(tracks not_allowed)
				(vias allowed)
				(pads allowed)
				(copperpour not_allowed)
				(footprints allowed)
			)
			(placement
				(enabled no)
				(sheetname "")
			)
			(fill
				(thermal_gap 0.5)
				(thermal_bridge_width 0.5)
				(island_removal_mode 0)
			)
			(polygon
				(pts
					(xy 368.2746 -137.0584) (xy 367.7666 -137.0584) (xy 367.7666 -136.6774) (xy 368.2746 -136.6774)
				)
			)
		)
		(zone
			(layer "F.Cu")
			(hatch none 0.5)
			(connect_pads
				(clearance 0)
			)
			(min_thickness 0.25)
			(keepout
				(tracks allowed)
				(vias not_allowed)
				(pads allowed)
				(copperpour not_allowed)
				(footprints allowed)
			)
			(placement
				(enabled no)
				(sheetname "")
			)
			(fill
				(thermal_gap 0.5)
				(thermal_bridge_width 0.5)
				(island_removal_mode 0)
			)
			(polygon
				(pts
					(xy 368.2746 -136.6774) (xy 367.7666 -136.6774) (xy 367.7666 -137.0584) (xy 368.2746 -137.0584)
				)
			)
		)
	)
	(footprint ""
		(layer "F.Cu")
		(at 197.162928 -53.221382 -90)
		(property "Reference" "C4E10"
			(at 0 0 270)
			(layer "F.SilkS")
			(hide yes)
			(effects
				(font
					(size 1.27 1.27)
				)
			)
		)
		(property "Value" ""
			(at 0 0 270)
			(layer "F.Fab")
			(effects
				(font
					(size 1.27 1.27)
				)
			)
		)
		(duplicate_pad_numbers_are_jumpers no)
		(fp_poly
			(pts
				(xy 0.3048 -0.1016) (xy 0.3048 0.9906) (xy -0.3048 0.9906) (xy -0.3048 -0.1016)
			)
			(stroke
				(width 0)
				(type default)
			)
			(fill no)
			(layer "F.CrtYd")
		)
		(fp_line
			(start -0.3048 0.9906)
			(end 0.3048 0.9906)
			(stroke
				(width 0.1)
				(type default)
			)
			(layer "F.Fab")
		)
		(fp_line
			(start 0.3048 0.9906)
			(end 0.3048 -0.1016)
			(stroke
				(width 0.1)
				(type default)
			)
			(layer "F.Fab")
		)
		(fp_line
			(start -0.3048 -0.1016)
			(end -0.3048 0.9906)
			(stroke
				(width 0.1)
				(type default)
			)
			(layer "F.Fab")
		)
		(fp_line
			(start 0.3048 -0.1016)
			(end -0.3048 -0.1016)
			(stroke
				(width 0.1)
				(type default)
			)
			(layer "F.Fab")
		)
		(pad "1" smd rect
			(at 0 0 270)
			(size 0.508 0.508)
			(layers "F.Cu" "F.Mask" "F.Paste")
			(net "VR_PVCCIN_CPU0_PH1_VCIN")
		)
		(pad "2" smd rect
			(at 0 0.889 270)
			(size 0.508 0.508)
			(layers "F.Cu" "F.Mask" "F.Paste")
			(net "GND")
		)
		(zone
			(layer "F.Cu")
			(hatch none 0.5)
			(connect_pads
				(clearance 0)
			)
			(min_thickness 0.25)
			(keepout
				(tracks not_allowed)
				(vias allowed)
				(pads allowed)
				(copperpour not_allowed)
				(footprints allowed)
			)
			(placement
				(enabled no)
				(sheetname "")
			)
			(fill
				(thermal_gap 0.5)
				(thermal_bridge_width 0.5)
				(island_removal_mode 0)
			)
			(polygon
				(pts
					(xy 196.527928 -53.475382) (xy 196.527928 -52.967382) (xy 196.908928 -52.967382) (xy 196.908928 -53.475382)
				)
			)
		)
		(zone
			(layer "F.Cu")
			(hatch none 0.5)
			(connect_pads
				(clearance 0)
			)
			(min_thickness 0.25)
			(keepout
				(tracks allowed)
				(vias not_allowed)
				(pads allowed)
				(copperpour not_allowed)
				(footprints allowed)
			)
			(placement
				(enabled no)
				(sheetname "")
			)
			(fill
				(thermal_gap 0.5)
				(thermal_bridge_width 0.5)
				(island_removal_mode 0)
			)
			(polygon
				(pts
					(xy 196.908928 -53.475382) (xy 196.908928 -52.967382) (xy 196.527928 -52.967382) (xy 196.527928 -53.475382)
				)
			)
		)
	)
	(footprint ""
		(layer "F.Cu")
		(at 107.134406 -68.365116 180)
		(property "Reference" "C3D25"
			(at 0 0 180)
			(layer "F.SilkS")
			(hide yes)
			(effects
				(font
					(size 1.27 1.27)
				)
			)
		)
		(property "Value" ""
			(at 0 0 180)
			(layer "F.Fab")
			(effects
				(font
					(size 1.27 1.27)
				)
			)
		)
		(duplicate_pad_numbers_are_jumpers no)
		(fp_poly
			(pts
				(xy -0.4953 -0.2032) (xy 0.4953 -0.2032) (xy 0.4953 1.6002) (xy -0.4953 1.6002)
			)
			(stroke
				(width 0)
				(type default)
			)
			(fill no)
			(layer "F.CrtYd")
		)
		(fp_line
			(start 0.4953 1.6002)
			(end -0.4953 1.6002)
			(stroke
				(width 0.1)
				(type default)
			)
			(layer "F.Fab")
		)
		(fp_line
			(start 0.4953 -0.2032)
			(end 0.4953 1.6002)
			(stroke
				(width 0.1)
				(type default)
			)
			(layer "F.Fab")
		)
		(fp_line
			(start -0.4953 1.6002)
			(end -0.4953 -0.2032)
			(stroke
				(width 0.1)
				(type default)
			)
			(layer "F.Fab")
		)
		(fp_line
			(start -0.4953 -0.2032)
			(end 0.4953 -0.2032)
			(stroke
				(width 0.1)
				(type default)
			)
			(layer "F.Fab")
		)
		(pad "1" smd rect
			(at 0 0 180)
			(size 0.762 0.889)
			(layers "F.Cu" "F.Mask" "F.Paste")
			(net "PVDDQ_GHJ")
		)
		(pad "2" smd rect
			(at 0 1.397 180)
			(size 0.762 0.889)
			(layers "F.Cu" "F.Mask" "F.Paste")
			(net "GND")
		)
		(zone
			(layer "F.Cu")
			(hatch none 0.5)
			(connect_pads
				(clearance 0)
			)
			(min_thickness 0.25)
			(keepout
				(tracks not_allowed)
				(vias allowed)
				(pads allowed)
				(copperpour not_allowed)
				(footprints allowed)
			)
			(placement
				(enabled no)
				(sheetname "")
			)
			(fill
				(thermal_gap 0.5)
				(thermal_bridge_width 0.5)
				(island_removal_mode 0)
			)
			(polygon
				(pts
					(xy 107.515406 -68.809616) (xy 106.753406 -68.809616) (xy 106.753406 -69.317616) (xy 107.515406 -69.317616)
				)
			)
		)
	)
)
